(kicad_pcb
	(version 20260206)
	(generator "pcbnew")
	(generator_version "10.0")
	(general
		(thickness 1.6)
		(legacy_teardrops no)
	)
	(paper "A4")
	(title_block
		(title "v1-chassis-manager — T6M_CM_d_v01_1031_1645.brd")
		(comment 1 "Open CloudServer (Microsoft) / footprints 1252-1261 of 2512")
	)
	(layers
		(0 "F.Cu" signal "TOP")
		(4 "In1.Cu" signal "GND1")
		(6 "In2.Cu" signal "IN1")
		(8 "In3.Cu" signal "VCC1")
		(10 "In4.Cu" signal "VCC2")
		(12 "In5.Cu" signal "GND2")
		(14 "In6.Cu" signal "IN2")
		(16 "In7.Cu" signal "IN3")
		(18 "In8.Cu" signal "GND3")
		(2 "B.Cu" signal "BOTTOM")
		(9 "F.Adhes" user "F.Adhesive")
		(11 "B.Adhes" user "B.Adhesive")
		(13 "F.Paste" user "Package Geometry/Pastemask Top")
		(15 "B.Paste" user "Package Geometry/Pastemask Bottom")
		(5 "F.SilkS" user "Ref Des/Silkscreen Top")
		(7 "B.SilkS" user "Ref Des/Silkscreen Bottom")
		(1 "F.Mask" user "Board Geometry/Soldermask Top")
		(3 "B.Mask" user "Board Geometry/Soldermask Bottom")
		(17 "Dwgs.User" user "User.Drawings")
		(19 "Cmts.User" user "User.Comments")
		(21 "Eco1.User" user "User.Eco1")
		(23 "Eco2.User" user "User.Eco2")
		(25 "Edge.Cuts" user "Board Geometry/Outline")
		(27 "Margin" user)
		(31 "F.CrtYd" user "Package Geometry/Place Bound Top")
		(29 "B.CrtYd" user "Package Geometry/Place Bound Bottom")
		(35 "F.Fab" user "Ref Des/Assembly Top")
		(33 "B.Fab" user "Ref Des/Assembly Bottom")
	)
	(footprint ""
		(layer "F.Cu")
		(at 52.223162 -149.578822)
		(property "Reference" "R560"
			(at -2.1336 5.265928 0)
			(unlocked yes)
			(layer "F.SilkS")
			(effects
				(font
					(size 0.7874 0.5842)
					(thickness 0.1524)
				)
				(justify left)
			)
		)
		(property "Value" ""
			(at 0 0 0)
			(layer "F.Fab")
			(effects
				(font
					(size 1.27 1.27)
				)
			)
		)
		(duplicate_pad_numbers_are_jumpers no)
		(fp_line
			(start -0.7874 -0.4064)
			(end 0.7874 -0.4064)
			(stroke
				(width 0.1524)
				(type default)
			)
			(layer "F.SilkS")
		)
		(fp_line
			(start -0.7874 0.4064)
			(end -0.7874 -0.4064)
			(stroke
				(width 0.1524)
				(type default)
			)
			(layer "F.SilkS")
		)
		(fp_line
			(start 0.7874 -0.4064)
			(end 0.7874 0.4064)
			(stroke
				(width 0.1524)
				(type default)
			)
			(layer "F.SilkS")
		)
		(fp_line
			(start 0.7874 0.4064)
			(end -0.7874 0.4064)
			(stroke
				(width 0.1524)
				(type default)
			)
			(layer "F.SilkS")
		)
		(fp_poly
			(pts
				(xy -0.508 0.2794) (xy -0.508 0.2286) (xy -0.635 0.2286) (xy -0.635 -0.254) (xy -0.5334 -0.254)
				(xy -0.5334 -0.2794) (xy 0.5334 -0.2794) (xy 0.5334 -0.254) (xy 0.635 -0.254) (xy 0.635 0.254) (xy 0.5334 0.254)
				(xy 0.5334 0.2794)
			)
			(stroke
				(width 0)
				(type default)
			)
			(fill no)
			(layer "F.CrtYd")
		)
		(pad "1" smd rect
			(at 0.40005 0)
			(size 0.4572 0.508)
			(layers "F.Cu" "F.Mask" "F.Paste")
			(net "FM_CPLD_NODE1_CPU_RESET_L")
		)
		(pad "2" smd rect
			(at -0.40005 0)
			(size 0.4572 0.508)
			(layers "F.Cu" "F.Mask" "F.Paste")
			(net "PLT_RST_LAN1_N")
		)
	)
	(footprint ""
		(layer "F.Cu")
		(at 163.565078 -12.4714 90)
		(property "Reference" "R1214"
			(at -0.888238 -2.014728 90)
			(unlocked yes)
			(layer "F.SilkS")
			(effects
				(font
					(size 0.7874 0.5842)
					(thickness 0.1524)
				)
				(justify left)
			)
		)
		(property "Value" ""
			(at 0 0 90)
			(layer "F.Fab")
			(effects
				(font
					(size 1.27 1.27)
				)
			)
		)
		(duplicate_pad_numbers_are_jumpers no)
		(fp_line
			(start 0.7874 -0.4064)
			(end 0.7874 0.4064)
			(stroke
				(width 0.1524)
				(type default)
			)
			(layer "F.SilkS")
		)
		(fp_line
			(start -0.7874 -0.4064)
			(end 0.7874 -0.4064)
			(stroke
				(width 0.1524)
				(type default)
			)
			(layer "F.SilkS")
		)
		(fp_line
			(start 0.7874 0.4064)
			(end -0.7874 0.4064)
			(stroke
				(width 0.1524)
				(type default)
			)
			(layer "F.SilkS")
		)
		(fp_line
			(start -0.7874 0.4064)
			(end -0.7874 -0.4064)
			(stroke
				(width 0.1524)
				(type default)
			)
			(layer "F.SilkS")
		)
		(fp_poly
			(pts
				(xy -0.508 0.2794) (xy -0.508 0.2286) (xy -0.635 0.2286) (xy -0.635 -0.254) (xy -0.5334 -0.254)
				(xy -0.5334 -0.2794) (xy 0.5334 -0.2794) (xy 0.5334 -0.254) (xy 0.635 -0.254) (xy 0.635 0.254) (xy 0.5334 0.254)
				(xy 0.5334 0.2794)
			)
			(stroke
				(width 0)
				(type default)
			)
			(fill no)
			(layer "F.CrtYd")
		)
		(pad "1" smd rect
			(at 0.40005 0 90)
			(size 0.4572 0.508)
			(layers "F.Cu" "F.Mask" "F.Paste")
			(net "P3V3_NODE1")
		)
		(pad "2" smd rect
			(at -0.40005 0 90)
			(size 0.4572 0.508)
			(layers "F.Cu" "F.Mask" "F.Paste")
			(net "JTAG_CPLD3_TDI")
		)
	)
	(footprint ""
		(layer "F.Cu")
		(at 78.123796 -162.099752 90)
		(property "Reference" "C580"
			(at -1.914652 -1.18999 90)
			(unlocked yes)
			(layer "F.SilkS")
			(effects
				(font
					(size 0.7874 0.5842)
					(thickness 0.1524)
				)
				(justify left)
			)
		)
		(property "Value" ""
			(at 0 0 90)
			(layer "F.Fab")
			(effects
				(font
					(size 1.27 1.27)
				)
			)
		)
		(duplicate_pad_numbers_are_jumpers no)
		(fp_line
			(start 0.7874 -0.4064)
			(end 0.7874 0.4064)
			(stroke
				(width 0.1524)
				(type default)
			)
			(layer "F.SilkS")
		)
		(fp_line
			(start -0.7874 -0.4064)
			(end 0.7874 -0.4064)
			(stroke
				(width 0.1524)
				(type default)
			)
			(layer "F.SilkS")
		)
		(fp_line
			(start 0 0.381)
			(end 0 -0.381)
			(stroke
				(width 0.1524)
				(type default)
			)
			(layer "F.SilkS")
		)
		(fp_line
			(start 0.7874 0.4064)
			(end -0.7874 0.4064)
			(stroke
				(width 0.1524)
				(type default)
			)
			(layer "F.SilkS")
		)
		(fp_line
			(start -0.7874 0.4064)
			(end -0.7874 -0.4064)
			(stroke
				(width 0.1524)
				(type default)
			)
			(layer "F.SilkS")
		)
		(fp_poly
			(pts
				(xy -0.5334 0.254) (xy -0.635 0.254) (xy -0.635 0.2286) (xy -0.635 -0.254) (xy -0.5334 -0.254) (xy -0.5334 -0.2794)
				(xy 0.5334 -0.2794) (xy 0.5334 -0.254) (xy 0.635 -0.254) (xy 0.635 0.254) (xy 0.5334 0.254) (xy 0.5334 0.2794)
				(xy -0.508 0.2794) (xy -0.5334 0.2794)
			)
			(stroke
				(width 0)
				(type default)
			)
			(fill no)
			(layer "F.CrtYd")
		)
		(pad "1" smd rect
			(at 0.40005 0 90)
			(size 0.4572 0.508)
			(layers "F.Cu" "F.Mask" "F.Paste")
			(net "P3V3_NODE1")
		)
		(pad "2" smd rect
			(at -0.40005 0 90)
			(size 0.4572 0.508)
			(layers "F.Cu" "F.Mask" "F.Paste")
			(net "GND")
		)
	)
	(footprint ""
		(layer "F.Cu")
		(at 47.60976 -178.804824 180)
		(property "Reference" "U99"
			(at 0.799084 -132.66293 90)
			(unlocked yes)
			(layer "F.SilkS")
			(effects
				(font
					(size 0.7874 0.5842)
					(thickness 0.1524)
				)
			)
		)
		(property "Value" ""
			(at 0 0 180)
			(layer "F.Fab")
			(effects
				(font
					(size 1.27 1.27)
				)
			)
		)
		(duplicate_pad_numbers_are_jumpers no)
		(fp_line
			(start 1.651 1.905)
			(end -1.651 1.905)
			(stroke
				(width 0.1524)
				(type default)
			)
			(layer "F.SilkS")
		)
		(fp_line
			(start 1.651 -1.905)
			(end 1.651 1.905)
			(stroke
				(width 0.1524)
				(type default)
			)
			(layer "F.SilkS")
		)
		(fp_line
			(start -1.651 1.905)
			(end -1.651 -1.905)
			(stroke
				(width 0.1524)
				(type default)
			)
			(layer "F.SilkS")
		)
		(fp_line
			(start -1.651 -1.905)
			(end 1.651 -1.905)
			(stroke
				(width 0.1524)
				(type default)
			)
			(layer "F.SilkS")
		)
		(fp_poly
			(pts
				(xy -1.524 0.7112) (xy -1.524 1.7526) (xy -0.508 1.7526) (xy -0.508 0.6985) (xy 0.508 0.6985) (xy 0.508 1.7526)
				(xy 1.524 1.7526) (xy 1.524 0.6985) (xy 1.524 -0.6985) (xy 0.508 -0.6985) (xy 0.508 -1.7526) (xy -0.508 -1.7526)
				(xy -0.508 -0.6985) (xy -1.524 -0.6985) (xy -1.524 0.6985)
			)
			(stroke
				(width 0)
				(type default)
			)
			(fill no)
			(layer "F.CrtYd")
		)
		(fp_text user "S"
			(at 1.988566 1.008634 0)
			(unlocked yes)
			(layer "F.SilkS")
			(effects
				(font
					(size 0.635 0.4064)
					(thickness 0.1524)
				)
			)
		)
		(fp_text user "G"
			(at -1.110742 2.328418 90)
			(unlocked yes)
			(layer "F.SilkS")
			(effects
				(font
					(size 0.635 0.4064)
					(thickness 0.1524)
				)
			)
		)
		(fp_text user "D"
			(at -1.253744 -2.37744 0)
			(unlocked yes)
			(layer "F.SilkS")
			(effects
				(font
					(size 0.635 0.4064)
					(thickness 0.1524)
				)
			)
		)
		(pad "D" smd rect
			(at 0 -1.1176 180)
			(size 1.016 1.27)
			(layers "F.Cu" "F.Mask" "F.Paste")
			(net "PSU_DC_OK_N")
		)
		(pad "G" smd rect
			(at -1.016 1.1176 180)
			(size 1.016 1.27)
			(layers "F.Cu" "F.Mask" "F.Paste")
			(net "PSU6_DC_OK_R_BUF")
		)
		(pad "S" smd rect
			(at 1.016 1.1176 180)
			(size 1.016 1.27)
			(layers "F.Cu" "F.Mask" "F.Paste")
			(net "GND")
		)
	)
	(footprint ""
		(layer "F.Cu")
		(at 115.43538 -130.40614 180)
		(property "Reference" "PR59"
			(at -0.512572 -3.68046 90)
			(unlocked yes)
			(layer "F.SilkS")
			(effects
				(font
					(size 0.7874 0.5842)
					(thickness 0.1524)
				)
				(justify left)
			)
		)
		(property "Value" ""
			(at 0 0 180)
			(layer "F.Fab")
			(effects
				(font
					(size 1.27 1.27)
				)
			)
		)
		(duplicate_pad_numbers_are_jumpers no)
		(fp_line
			(start 0.7874 0.4064)
			(end -0.7874 0.4064)
			(stroke
				(width 0.1524)
				(type default)
			)
			(layer "F.SilkS")
		)
		(fp_line
			(start 0.7874 -0.4064)
			(end 0.7874 0.4064)
			(stroke
				(width 0.1524)
				(type default)
			)
			(layer "F.SilkS")
		)
		(fp_line
			(start -0.7874 0.4064)
			(end -0.7874 -0.4064)
			(stroke
				(width 0.1524)
				(type default)
			)
			(layer "F.SilkS")
		)
		(fp_line
			(start -0.7874 -0.4064)
			(end 0.7874 -0.4064)
			(stroke
				(width 0.1524)
				(type default)
			)
			(layer "F.SilkS")
		)
		(fp_poly
			(pts
				(xy -0.508 0.2794) (xy -0.508 0.2286) (xy -0.635 0.2286) (xy -0.635 -0.254) (xy -0.5334 -0.254)
				(xy -0.5334 -0.2794) (xy 0.5334 -0.2794) (xy 0.5334 -0.254) (xy 0.635 -0.254) (xy 0.635 0.254) (xy 0.5334 0.254)
				(xy 0.5334 0.2794)
			)
			(stroke
				(width 0)
				(type default)
			)
			(fill no)
			(layer "F.CrtYd")
		)
		(pad "1" smd rect
			(at 0.40005 0 180)
			(size 0.4572 0.508)
			(layers "F.Cu" "F.Mask" "F.Paste")
			(net "VR_PVCCP_NODE1_ISEN1P_RR")
		)
		(pad "2" smd rect
			(at -0.40005 0 180)
			(size 0.4572 0.508)
			(layers "F.Cu" "F.Mask" "F.Paste")
			(net "ISENSE_PVCCP_NODE1_ISEN1N")
		)
	)
	(footprint ""
		(layer "F.Cu")
		(at 106.192066 -163.767516)
		(property "Reference" "R769"
			(at 85.291168 69.771768 0)
			(unlocked yes)
			(layer "F.SilkS")
			(effects
				(font
					(size 0.7874 0.5842)
					(thickness 0.1524)
				)
				(justify left)
			)
		)
		(property "Value" ""
			(at 0 0 0)
			(layer "F.Fab")
			(effects
				(font
					(size 1.27 1.27)
				)
			)
		)
		(duplicate_pad_numbers_are_jumpers no)
		(fp_line
			(start -0.7874 -0.4064)
			(end 0.7874 -0.4064)
			(stroke
				(width 0.1524)
				(type default)
			)
			(layer "F.SilkS")
		)
		(fp_line
			(start -0.7874 0.4064)
			(end -0.7874 -0.4064)
			(stroke
				(width 0.1524)
				(type default)
			)
			(layer "F.SilkS")
		)
		(fp_line
			(start 0.7874 -0.4064)
			(end 0.7874 0.4064)
			(stroke
				(width 0.1524)
				(type default)
			)
			(layer "F.SilkS")
		)
		(fp_line
			(start 0.7874 0.4064)
			(end -0.7874 0.4064)
			(stroke
				(width 0.1524)
				(type default)
			)
			(layer "F.SilkS")
		)
		(fp_poly
			(pts
				(xy -0.508 0.2794) (xy -0.508 0.2286) (xy -0.635 0.2286) (xy -0.635 -0.254) (xy -0.5334 -0.254)
				(xy -0.5334 -0.2794) (xy 0.5334 -0.2794) (xy 0.5334 -0.254) (xy 0.635 -0.254) (xy 0.635 0.254) (xy 0.5334 0.254)
				(xy 0.5334 0.2794)
			)
			(stroke
				(width 0)
				(type default)
			)
			(fill no)
			(layer "F.CrtYd")
		)
		(pad "1" smd rect
			(at 0.40005 0)
			(size 0.4572 0.508)
			(layers "F.Cu" "F.Mask" "F.Paste")
			(net "P3V3_NODE1")
		)
		(pad "2" smd rect
			(at -0.40005 0)
			(size 0.4572 0.508)
			(layers "F.Cu" "F.Mask" "F.Paste")
			(net "PU_FAN_TACH")
		)
	)
	(footprint ""
		(layer "F.Cu")
		(at 85.390228 -133.213094 -90)
		(property "Reference" "D34"
			(at 5.3213 3.152902 90)
			(unlocked yes)
			(layer "F.SilkS")
			(effects
				(font
					(size 0.7874 0.5842)
					(thickness 0.1524)
				)
				(justify left)
			)
		)
		(property "Value" ""
			(at 0 0 270)
			(layer "F.Fab")
			(effects
				(font
					(size 1.27 1.27)
				)
			)
		)
		(duplicate_pad_numbers_are_jumpers no)
		(fp_line
			(start -1.3208 0.5588)
			(end -1.3208 -0.5588)
			(stroke
				(width 0.1524)
				(type default)
			)
			(layer "F.SilkS")
		)
		(fp_line
			(start 1.3208 0.5588)
			(end -1.3208 0.5588)
			(stroke
				(width 0.1524)
				(type default)
			)
			(layer "F.SilkS")
		)
		(fp_line
			(start 1.6256 0.5588)
			(end 1.6256 -0.5588)
			(stroke
				(width 0.1524)
				(type default)
			)
			(layer "F.SilkS")
		)
		(fp_line
			(start 1.778 0.5588)
			(end 1.3208 0.5588)
			(stroke
				(width 0.1524)
				(type default)
			)
			(layer "F.SilkS")
		)
		(fp_line
			(start -1.3208 -0.5588)
			(end 1.3208 -0.5588)
			(stroke
				(width 0.1524)
				(type default)
			)
			(layer "F.SilkS")
		)
		(fp_line
			(start 1.3208 -0.5588)
			(end 1.3208 0.5588)
			(stroke
				(width 0.1524)
				(type default)
			)
			(layer "F.SilkS")
		)
		(fp_line
			(start 1.4732 -0.5588)
			(end 1.4732 0.5588)
			(stroke
				(width 0.1524)
				(type default)
			)
			(layer "F.SilkS")
		)
		(fp_line
			(start 1.778 -0.5588)
			(end 1.778 0.5588)
			(stroke
				(width 0.1524)
				(type default)
			)
			(layer "F.SilkS")
		)
		(fp_line
			(start 1.778 -0.5588)
			(end 1.3208 -0.5588)
			(stroke
				(width 0.1524)
				(type default)
			)
			(layer "F.SilkS")
		)
		(fp_circle
			(center 2.4384 0)
			(end 2.4384 -0.413512)
			(stroke
				(width 0.1524)
				(type default)
			)
			(fill no)
			(layer "F.SilkS")
		)
		(fp_rect
			(start -1.1684 0.508)
			(end 1.1684 -0.508)
			(stroke
				(width 0)
				(type default)
			)
			(fill no)
			(layer "F.CrtYd")
		)
		(fp_text user "-"
			(at 2.218182 0.635 270)
			(unlocked yes)
			(layer "F.SilkS")
			(effects
				(font
					(size 0.7874 0.5842)
					(thickness 0.1524)
				)
				(justify left)
			)
		)
		(pad "A" smd rect
			(at -0.750062 0 270)
			(size 0.8128 0.8128)
			(layers "F.Cu" "F.Mask" "F.Paste")
			(net "P3V3_NODE1")
		)
		(pad "C" smd rect
			(at 0.750062 0 270)
			(size 0.8128 0.8128)
			(layers "F.Cu" "F.Mask" "F.Paste")
			(net "N53313501")
		)
	)
	(footprint ""
		(layer "F.Cu")
		(at 33.566608 -127.363728 90)
		(property "Reference" "C830"
			(at -1.219708 1.625346 90)
			(unlocked yes)
			(layer "F.SilkS")
			(effects
				(font
					(size 0.7874 0.5842)
					(thickness 0.1524)
				)
				(justify left)
			)
		)
		(property "Value" ""
			(at 0 0 90)
			(layer "F.Fab")
			(effects
				(font
					(size 1.27 1.27)
				)
			)
		)
		(duplicate_pad_numbers_are_jumpers no)
		(fp_line
			(start 1.905 -0.8636)
			(end 1.905 0.8636)
			(stroke
				(width 0.1524)
				(type default)
			)
			(layer "F.SilkS")
		)
		(fp_line
			(start -1.905 -0.8636)
			(end 1.905 -0.8636)
			(stroke
				(width 0.1524)
				(type default)
			)
			(layer "F.SilkS")
		)
		(fp_line
			(start 0 0.8382)
			(end 0 -0.8382)
			(stroke
				(width 0.1524)
				(type default)
			)
			(layer "F.SilkS")
		)
		(fp_line
			(start 1.905 0.8636)
			(end -1.905 0.8636)
			(stroke
				(width 0.1524)
				(type default)
			)
			(layer "F.SilkS")
		)
		(fp_line
			(start -1.905 0.8636)
			(end -1.905 -0.8636)
			(stroke
				(width 0.1524)
				(type default)
			)
			(layer "F.SilkS")
		)
		(fp_rect
			(start -1.524 0.7366)
			(end 1.524 -0.7366)
			(stroke
				(width 0)
				(type default)
			)
			(fill no)
			(layer "F.CrtYd")
		)
		(pad "1" smd rect
			(at 0.94996 0 90)
			(size 1.1176 1.3716)
			(layers "F.Cu" "F.Mask" "F.Paste")
			(net "P1V538_BMC_NODE1")
		)
		(pad "2" smd rect
			(at -0.94996 0 90)
			(size 1.1176 1.3716)
			(layers "F.Cu" "F.Mask" "F.Paste")
			(net "GND")
		)
	)
	(footprint ""
		(layer "F.Cu")
		(at 133.46176 -188.126624 -90)
		(property "Reference" "R986"
			(at -4.949444 1.084072 90)
			(unlocked yes)
			(layer "F.SilkS")
			(effects
				(font
					(size 0.7874 0.5842)
					(thickness 0.1524)
				)
				(justify left)
			)
		)
		(property "Value" ""
			(at 0 0 270)
			(layer "F.Fab")
			(effects
				(font
					(size 1.27 1.27)
				)
			)
		)
		(duplicate_pad_numbers_are_jumpers no)
		(fp_line
			(start -0.7874 0.4064)
			(end -0.7874 -0.4064)
			(stroke
				(width 0.1524)
				(type default)
			)
			(layer "F.SilkS")
		)
		(fp_line
			(start 0.7874 0.4064)
			(end -0.7874 0.4064)
			(stroke
				(width 0.1524)
				(type default)
			)
			(layer "F.SilkS")
		)
		(fp_line
			(start -0.7874 -0.4064)
			(end 0.7874 -0.4064)
			(stroke
				(width 0.1524)
				(type default)
			)
			(layer "F.SilkS")
		)
		(fp_line
			(start 0.7874 -0.4064)
			(end 0.7874 0.4064)
			(stroke
				(width 0.1524)
				(type default)
			)
			(layer "F.SilkS")
		)
		(fp_poly
			(pts
				(xy -0.508 0.2794) (xy -0.508 0.2286) (xy -0.635 0.2286) (xy -0.635 -0.254) (xy -0.5334 -0.254)
				(xy -0.5334 -0.2794) (xy 0.5334 -0.2794) (xy 0.5334 -0.254) (xy 0.635 -0.254) (xy 0.635 0.254) (xy 0.5334 0.254)
				(xy 0.5334 0.2794)
			)
			(stroke
				(width 0)
				(type default)
			)
			(fill no)
			(layer "F.CrtYd")
		)
		(pad "1" smd rect
			(at 0.40005 0 270)
			(size 0.4572 0.508)
			(layers "F.Cu" "F.Mask" "F.Paste")
			(net "UART_T10_NODE2_RXD")
		)
		(pad "2" smd rect
			(at -0.40005 0 270)
			(size 0.4572 0.508)
			(layers "F.Cu" "F.Mask" "F.Paste")
			(net "UART_T10_NODE2_RXD_R")
		)
	)
	(footprint ""
		(layer "F.Cu")
		(at 49.38776 -182.238142 90)
		(property "Reference" "C608"
			(at -133.313932 -3.637788 90)
			(unlocked yes)
			(layer "F.SilkS")
			(effects
				(font
					(size 0.7874 0.5842)
					(thickness 0.1524)
				)
				(justify left)
			)
		)
		(property "Value" ""
			(at 0 0 90)
			(layer "F.Fab")
			(effects
				(font
					(size 1.27 1.27)
				)
			)
		)
		(duplicate_pad_numbers_are_jumpers no)
		(fp_line
			(start 0.7874 -0.4064)
			(end 0.7874 0.4064)
			(stroke
				(width 0.1524)
				(type default)
			)
			(layer "F.SilkS")
		)
		(fp_line
			(start -0.7874 -0.4064)
			(end 0.7874 -0.4064)
			(stroke
				(width 0.1524)
				(type default)
			)
			(layer "F.SilkS")
		)
		(fp_line
			(start 0 0.381)
			(end 0 -0.381)
			(stroke
				(width 0.1524)
				(type default)
			)
			(layer "F.SilkS")
		)
		(fp_line
			(start 0.7874 0.4064)
			(end -0.7874 0.4064)
			(stroke
				(width 0.1524)
				(type default)
			)
			(layer "F.SilkS")
		)
		(fp_line
			(start -0.7874 0.4064)
			(end -0.7874 -0.4064)
			(stroke
				(width 0.1524)
				(type default)
			)
			(layer "F.SilkS")
		)
		(fp_poly
			(pts
				(xy -0.5334 0.254) (xy -0.635 0.254) (xy -0.635 0.2286) (xy -0.635 -0.254) (xy -0.5334 -0.254) (xy -0.5334 -0.2794)
				(xy 0.5334 -0.2794) (xy 0.5334 -0.254) (xy 0.635 -0.254) (xy 0.635 0.254) (xy 0.5334 0.254) (xy 0.5334 0.2794)
				(xy -0.508 0.2794) (xy -0.5334 0.2794)
			)
			(stroke
				(width 0)
				(type default)
			)
			(fill no)
			(layer "F.CrtYd")
		)
		(pad "1" smd rect
			(at 0.40005 0 90)
			(size 0.4572 0.508)
			(layers "F.Cu" "F.Mask" "F.Paste")
			(net "PSU4_AC_OK")
		)
		(pad "2" smd rect
			(at -0.40005 0 90)
			(size 0.4572 0.508)
			(layers "F.Cu" "F.Mask" "F.Paste")
			(net "GND")
		)
	)
)
